(kicad_pcb
	(version 20260206)
	(generator "pcbnew")
	(generator_version "10.0")
	(general
		(thickness 1.6)
		(legacy_teardrops no)
	)
	(paper "A4")
	(title_block
		(title "v1-chassis-manager — T6M_CM_d_v01_1031_1645.brd")
		(comment 1 "Open CloudServer (Microsoft) / footprints 512-512 of 2512")
	)
	(layers
		(0 "F.Cu" signal "TOP")
		(4 "In1.Cu" signal "GND1")
		(6 "In2.Cu" signal "IN1")
		(8 "In3.Cu" signal "VCC1")
		(10 "In4.Cu" signal "VCC2")
		(12 "In5.Cu" signal "GND2")
		(14 "In6.Cu" signal "IN2")
		(16 "In7.Cu" signal "IN3")
		(18 "In8.Cu" signal "GND3")
		(2 "B.Cu" signal "BOTTOM")
		(9 "F.Adhes" user "F.Adhesive")
		(11 "B.Adhes" user "B.Adhesive")
		(13 "F.Paste" user "Package Geometry/Pastemask Top")
		(15 "B.Paste" user "Package Geometry/Pastemask Bottom")
		(5 "F.SilkS" user "Ref Des/Silkscreen Top")
		(7 "B.SilkS" user "Ref Des/Silkscreen Bottom")
		(1 "F.Mask" user "Board Geometry/Soldermask Top")
		(3 "B.Mask" user "Board Geometry/Soldermask Bottom")
		(17 "Dwgs.User" user "User.Drawings")
		(19 "Cmts.User" user "User.Comments")
		(21 "Eco1.User" user "User.Eco1")
		(23 "Eco2.User" user "User.Eco2")
		(25 "Edge.Cuts" user "Board Geometry/Outline")
		(27 "Margin" user)
		(31 "F.CrtYd" user "Package Geometry/Place Bound Top")
		(29 "B.CrtYd" user "Package Geometry/Place Bound Bottom")
		(35 "F.Fab" user "Ref Des/Assembly Top")
		(33 "B.Fab" user "Ref Des/Assembly Bottom")
	)
	(footprint ""
		(layer "F.Cu")
		(at 8.75157 -83.828128 -90)
		(property "Reference" "J19"
			(at -5.454396 -2.26695 0)
			(unlocked yes)
			(layer "F.SilkS")
			(effects
				(font
					(size 0.7874 0.5842)
					(thickness 0.1524)
				)
				(justify left)
			)
		)
		(property "Value" ""
			(at 0 0 270)
			(layer "F.Fab")
			(effects
				(font
					(size 1.27 1.27)
				)
			)
		)
		(duplicate_pad_numbers_are_jumpers no)
		(fp_line
			(start -1.700022 5.999988)
			(end 1.700022 5.999988)
			(stroke
				(width 0.1524)
				(type default)
			)
			(layer "F.SilkS")
		)
		(fp_line
			(start -1.700022 5.999988)
			(end -1.700022 4.59994)
			(stroke
				(width 0.1524)
				(type default)
			)
			(layer "F.SilkS")
		)
		(fp_line
			(start 1.700022 5.999988)
			(end 1.700022 4.59994)
			(stroke
				(width 0.1524)
				(type default)
			)
			(layer "F.SilkS")
		)
		(fp_line
			(start -4.800092 4.59994)
			(end -4.800092 -4.99999)
			(stroke
				(width 0.1524)
				(type default)
			)
			(layer "F.SilkS")
		)
		(fp_line
			(start 4.800092 4.59994)
			(end -4.800092 4.59994)
			(stroke
				(width 0.1524)
				(type default)
			)
			(layer "F.SilkS")
		)
		(fp_line
			(start -8.6614 4.1402)
			(end -4.8006 4.1402)
			(stroke
				(width 0.1524)
				(type default)
			)
			(layer "F.SilkS")
		)
		(fp_line
			(start -4.8006 4.1402)
			(end -4.8006 3.937)
			(stroke
				(width 0.1524)
				(type default)
			)
			(layer "F.SilkS")
		)
		(fp_line
			(start 4.8006 4.1402)
			(end 4.8006 4.1148)
			(stroke
				(width 0.1524)
				(type default)
			)
			(layer "F.SilkS")
		)
		(fp_line
			(start 8.6614 4.1402)
			(end 4.8006 4.1402)
			(stroke
				(width 0.1524)
				(type default)
			)
			(layer "F.SilkS")
		)
		(fp_line
			(start -8.6614 0.4318)
			(end -8.6614 4.1402)
			(stroke
				(width 0.1524)
				(type default)
			)
			(layer "F.SilkS")
		)
		(fp_line
			(start -4.8514 0.4318)
			(end -8.6614 0.4318)
			(stroke
				(width 0.1524)
				(type default)
			)
			(layer "F.SilkS")
		)
		(fp_line
			(start 4.8514 0.4318)
			(end 8.6868 0.4318)
			(stroke
				(width 0.1524)
				(type default)
			)
			(layer "F.SilkS")
		)
		(fp_line
			(start 8.6868 0.4318)
			(end 8.6614 4.1402)
			(stroke
				(width 0.1524)
				(type default)
			)
			(layer "F.SilkS")
		)
		(fp_line
			(start -4.800092 -4.99999)
			(end 4.800092 -4.99999)
			(stroke
				(width 0.1524)
				(type default)
			)
			(layer "F.SilkS")
		)
		(fp_line
			(start 4.800092 -4.99999)
			(end 4.800092 4.59994)
			(stroke
				(width 0.1524)
				(type default)
			)
			(layer "F.SilkS")
		)
		(fp_poly
			(pts
				(xy -1.7272 -5.2324) (xy -1.9558 -5.9944) (xy -1.4478 -5.9944)
			)
			(stroke
				(width 0)
				(type default)
			)
			(fill yes)
			(layer "F.SilkS")
		)
		(fp_poly
			(pts
				(xy 3.1242 1.7272) (xy -3.1242 1.7272) (xy -3.1242 3.7846) (xy 3.1242 3.7846)
			)
			(stroke
				(width 0)
				(type default)
			)
			(fill no)
			(layer "B.CrtYd")
		)
		(fp_poly
			(pts
				(xy -3.1242 -3.7846) (xy 3.1242 -3.7846) (xy 3.1242 -1.7272) (xy -3.1242 -1.7272)
			)
			(stroke
				(width 0)
				(type default)
			)
			(fill no)
			(layer "B.CrtYd")
		)
		(fp_poly
			(pts
				(arc
					(start 8.324088 2.290064)
					(mid 6.800088 0.766064)
					(end 5.276088 2.290064)
				)
				(arc
					(start 5.276088 2.315464)
					(mid 5.715018 3.375134)
					(end 6.774688 3.814064)
				)
				(arc
					(start 6.825488 3.814064)
					(mid 7.885158 3.375134)
					(end 8.324088 2.315464)
				)
			)
			(stroke
				(width 0)
				(type default)
			)
			(fill no)
			(layer "B.CrtYd")
		)
		(fp_poly
			(pts
				(arc
					(start -5.2832 2.286)
					(mid -6.8072 0.762)
					(end -8.3312 2.286)
				)
				(arc
					(start -8.3312 2.3114)
					(mid -7.89227 3.37107)
					(end -6.8326 3.81)
				)
				(arc
					(start -6.7818 3.81)
					(mid -5.72213 3.37107)
					(end -5.2832 2.3114)
				)
			)
			(stroke
				(width 0)
				(type default)
			)
			(fill no)
			(layer "B.CrtYd")
		)
		(fp_poly
			(pts
				(xy -1.7018 5.9944) (xy -1.7018 4.5974) (xy -4.8006 4.5974) (xy -4.8006 4.1402) (xy -8.255 4.1402)
				(xy -8.6614 4.1402) (xy -8.6614 0.4318) (xy -8.255 0.4318) (xy -4.826 0.4318) (xy -4.826 0.254)
				(xy -4.826 -5.0038) (xy 4.826 -5.0038) (xy 4.826 0.254) (xy 4.826 0.4318) (xy 8.255 0.4318) (xy 8.6614 0.4318)
				(xy 8.6614 4.1402) (xy 8.255 4.1402) (xy 4.8006 4.1402) (xy 4.8006 4.5974) (xy 1.7018 4.5974) (xy 1.7018 5.9944)
			)
			(stroke
				(width 0)
				(type default)
			)
			(fill no)
			(layer "F.CrtYd")
		)
		(fp_text user "3"
			(at -2.27203 5.596382 0)
			(unlocked yes)
			(layer "F.SilkS")
			(effects
				(font
					(size 0.7874 0.5842)
					(thickness 0.1524)
				)
				(justify left)
			)
		)
		(fp_text user "4"
			(at 2.614676 5.559298 0)
			(unlocked yes)
			(layer "F.SilkS")
			(effects
				(font
					(size 0.7874 0.5842)
					(thickness 0.1524)
				)
				(justify left)
			)
		)
		(fp_text user "1"
			(at -2.91211 -5.273802 0)
			(unlocked yes)
			(layer "F.SilkS")
			(effects
				(font
					(size 0.7874 0.5842)
					(thickness 0.1524)
				)
				(justify left)
			)
		)
		(fp_text user "2"
			(at 3.11912 -5.41147 0)
			(unlocked yes)
			(layer "F.SilkS")
			(effects
				(font
					(size 0.7874 0.5842)
					(thickness 0.1524)
				)
				(justify left)
			)
		)
		(fp_text user "4"
			(at 2.137156 4.300982 0)
			(unlocked yes)
			(layer "B.SilkS")
			(effects
				(font
					(size 0.7874 0.5842)
					(thickness 0.1524)
				)
				(justify left mirror)
			)
		)
		(fp_text user "3"
			(at -2.16662 4.113784 0)
			(unlocked yes)
			(layer "B.SilkS")
			(effects
				(font
					(size 0.7874 0.5842)
					(thickness 0.1524)
				)
				(justify left mirror)
			)
		)
		(fp_text user "1"
			(at -2.096516 -4.704334 0)
			(unlocked yes)
			(layer "B.SilkS")
			(effects
				(font
					(size 0.7874 0.5842)
					(thickness 0.1524)
				)
				(justify left mirror)
			)
		)
		(fp_text user "2"
			(at 2.183892 -4.844796 0)
			(unlocked yes)
			(layer "B.SilkS")
			(effects
				(font
					(size 0.7874 0.5842)
					(thickness 0.1524)
				)
				(justify left mirror)
			)
		)
		(pad "" np_thru_hole circle
			(at -6.800088 2.290064 270)
			(size 3.048 3.048)
			(drill 3.048)
			(layers "*.Cu" "*.Mask")
			(clearance 0.381)
			(thermal_gap 0.381)
		)
		(pad "" np_thru_hole circle
			(at 6.800088 2.290064 270)
			(size 3.048 3.048)
			(drill 3.048)
			(layers "*.Cu" "*.Mask")
			(clearance 0.381)
			(thermal_gap 0.381)
		)
		(pad "1" thru_hole rect
			(at -2.100072 -2.750058 270)
			(size 1.9558 1.9558)
			(drill 1.4478)
			(layers "*.Cu" "*.Mask")
			(remove_unused_layers no)
			(net "GND")
			(clearance 0)
			(padstack
				(mode front_inner_back)
				(layer "Inner"
					(shape circle)
					(size 1.9558 1.9558)
					(clearance 0)
				)
				(layer "B.Cu"
					(shape rect)
					(size 1.9558 1.9558)
					(clearance 0)
				)
			)
		)
		(pad "2" thru_hole circle
			(at 2.100072 -2.750058 270)
			(size 1.9558 1.9558)
			(drill 1.4478)
			(layers "*.Cu" "*.Mask")
			(remove_unused_layers no)
			(net "GND")
			(clearance 0)
		)
		(pad "3" thru_hole circle
			(at -2.100072 2.750058 270)
			(size 1.9558 1.9558)
			(drill 1.4478)
			(layers "*.Cu" "*.Mask")
			(remove_unused_layers no)
			(net "P12V_DBG")
			(clearance 0)
		)
		(pad "4" thru_hole circle
			(at 2.100072 2.750058 270)
			(size 1.9558 1.9558)
			(drill 1.4478)
			(layers "*.Cu" "*.Mask")
			(remove_unused_layers no)
			(net "P12V_DBG")
			(clearance 0)
		)
		(zone
			(layers "F.Cu" "B.Cu" "In1.Cu" "In2.Cu" "In3.Cu" "In4.Cu" "In5.Cu" "In6.Cu"
				"In7.Cu" "In8.Cu"
			)
			(hatch none 0.5)
			(connect_pads
				(clearance 0)
			)
			(min_thickness 0.25)
			(keepout
				(tracks not_allowed)
				(vias allowed)
				(pads allowed)
				(copperpour not_allowed)
				(footprints allowed)
			)
			(placement
				(enabled no)
				(sheetname "")
			)
			(fill
				(thermal_gap 0.5)
				(thermal_bridge_width 0.5)
				(island_removal_mode 0)
			)
			(polygon
				(pts
					(arc
						(start 4.53517 -90.635328)
						(mid 8.39597 -90.635328)
						(end 4.53517 -90.635328)
					)
				)
			)
		)
		(zone
			(layers "F.Cu" "B.Cu" "In1.Cu" "In2.Cu" "In3.Cu" "In4.Cu" "In5.Cu" "In6.Cu"
				"In7.Cu" "In8.Cu"
			)
			(hatch none 0.5)
			(connect_pads
				(clearance 0)
			)
			(min_thickness 0.25)
			(keepout
				(tracks not_allowed)
				(vias allowed)
				(pads allowed)
				(copperpour not_allowed)
				(footprints allowed)
			)
			(placement
				(enabled no)
				(sheetname "")
			)
			(fill
				(thermal_gap 0.5)
				(thermal_bridge_width 0.5)
				(island_removal_mode 0)
			)
			(polygon
				(pts
					(arc
						(start 4.53517 -77.020928)
						(mid 8.39597 -77.020928)
						(end 4.53517 -77.020928)
					)
				)
			)
		)
	)
)
